FILE_TYPE=LIBRARY_PARTS;
primitive 'IR354XX','IR354XX_SM';
  pin
    'BOOST':
      PIN_NUMBER='(33)';
      BIDIRECTIONAL='TRUE';
      INPUT_LOAD='(-0.01,0.01)';
      OUTPUT_LOAD='(1.0,-1.0)';
    'EN':
      PIN_NUMBER='(35)';
      BIDIRECTIONAL='TRUE';
      INPUT_LOAD='(-0.01,0.01)';
      OUTPUT_LOAD='(1.0,-1.0)';
    'GL'<1>:
      PIN_NUMBER='(41)';
      BIDIRECTIONAL='TRUE';
      INPUT_LOAD='(-0.01,0.01)';
      OUTPUT_LOAD='(1.0,-1.0)';
    'GL'<0>:
      PIN_NUMBER='(6)';
      BIDIRECTIONAL='TRUE';
      INPUT_LOAD='(-0.01,0.01)';
      OUTPUT_LOAD='(1.0,-1.0)';
    'IOUT':
      PIN_NUMBER='(38)';
      OUTPUT_LOAD='(1.0,-1.0)';
    'LGND':
      PIN_NUMBER='(2)';
      PINUSE='GROUND';
      NO_LOAD_CHECK='Both';
      NO_IO_CHECK='Both';
      NO_ASSERT_CHECK='TRUE';
      NO_DIR_CHECK='TRUE';
      ALLOW_CONNECT='TRUE';
    'NC':
      PIN_NUMBER='(31)';
      PINUSE='NC';
      NO_LOAD_CHECK='Both';
      NO_IO_CHECK='Both';
      NO_ASSERT_CHECK='TRUE';
      NO_DIR_CHECK='TRUE';
      ALLOW_CONNECT='TRUE';
    'OCSET':
      PIN_NUMBER='(37)';
      BIDIRECTIONAL='TRUE';
      INPUT_LOAD='(-0.01,0.01)';
      OUTPUT_LOAD='(1.0,-1.0)';
    'PGND'<2>:
      PIN_NUMBER='(40)';
      PINUSE='GROUND';
      NO_LOAD_CHECK='Both';
      NO_IO_CHECK='Both';
      NO_ASSERT_CHECK='TRUE';
      NO_DIR_CHECK='TRUE';
      ALLOW_CONNECT='TRUE';
    'PGND'<1>:
      PIN_NUMBER='(7)';
      PINUSE='GROUND';
      NO_LOAD_CHECK='Both';
      NO_IO_CHECK='Both';
      NO_ASSERT_CHECK='TRUE';
      NO_DIR_CHECK='TRUE';
      ALLOW_CONNECT='TRUE';
    'PGND'<0>:
      PIN_NUMBER='(5)';
      PINUSE='GROUND';
      NO_LOAD_CHECK='Both';
      NO_IO_CHECK='Both';
      NO_ASSERT_CHECK='TRUE';
      NO_DIR_CHECK='TRUE';
      ALLOW_CONNECT='TRUE';
    'PHASE':
      PIN_NUMBER='(32)';
      BIDIRECTIONAL='TRUE';
      INPUT_LOAD='(-0.01,0.01)';
      OUTPUT_LOAD='(1.0,-1.0)';
    'PWM':
      PIN_NUMBER='(34)';
      INPUT_LOAD='(-0.01,0.01)';
    'REFIN':
      PIN_NUMBER='(39)';
      INPUT_LOAD='(-0.01,0.01)';
    'SW':
      PIN_NUMBER='(10)';
      BIDIRECTIONAL='TRUE';
      INPUT_LOAD='(-0.01,0.01)';
      OUTPUT_LOAD='(1.0,-1.0)';
    'TOUT_FLT':
      PIN_NUMBER='(36)';
      BIDIRECTIONAL='TRUE';
      INPUT_LOAD='(-0.01,0.01)';
      OUTPUT_LOAD='(1.0,-1.0)';
    'VCC':
      PIN_NUMBER='(3)';
      PINUSE='POWER';
      NO_LOAD_CHECK='Both';
      NO_IO_CHECK='Both';
      NO_ASSERT_CHECK='TRUE';
      NO_DIR_CHECK='TRUE';
      ALLOW_CONNECT='TRUE';
    'VDRV':
      PIN_NUMBER='(4)';
      BIDIRECTIONAL='TRUE';
      INPUT_LOAD='(-0.01,0.01)';
      OUTPUT_LOAD='(1.0,-1.0)';
    'VIN'<1>:
      PIN_NUMBER='(30)';
      PINUSE='POWER';
      NO_LOAD_CHECK='Both';
      NO_IO_CHECK='Both';
      NO_ASSERT_CHECK='TRUE';
      NO_DIR_CHECK='TRUE';
      ALLOW_CONNECT='TRUE';
    'VIN'<0>:
      PIN_NUMBER='(25)';
      PINUSE='POWER';
      NO_LOAD_CHECK='Both';
      NO_IO_CHECK='Both';
      NO_ASSERT_CHECK='TRUE';
      NO_DIR_CHECK='TRUE';
      ALLOW_CONNECT='TRUE';
    'VOS':
      PIN_NUMBER='(1)';
      BIDIRECTIONAL='TRUE';
      INPUT_LOAD='(-0.01,0.01)';
      OUTPUT_LOAD='(1.0,-1.0)';
  end_pin;
  body
    PART_NAME='IR354XX';
    PHYS_DES_PREFIX='EU';
  end_body;
end_primitive;

END.
